(kicad_pcb
	(version 20260206)
	(generator "pcbnew")
	(generator_version "10.0")
	(general
		(thickness 1.6)
		(legacy_teardrops no)
	)
	(paper "A4")
	(title_block
		(title "netronome-mezz — pcbd0082-001_rev01_jul9_a.brd")
		(comment 1 "Open CloudServer (Microsoft) / footprints 220-220 of 714")
	)
	(layers
		(0 "F.Cu" signal "TOP")
		(4 "In1.Cu" signal "02_GND")
		(6 "In2.Cu" signal "03_SIG")
		(8 "In3.Cu" signal "04_SIG")
		(10 "In4.Cu" signal "05_GND")
		(12 "In5.Cu" signal "06_PWR1")
		(14 "In6.Cu" signal "07_SIG")
		(16 "In7.Cu" signal "08_SIG")
		(18 "In8.Cu" signal "09_GND")
		(2 "B.Cu" signal "BOTTOM")
		(9 "F.Adhes" user "F.Adhesive")
		(11 "B.Adhes" user "B.Adhesive")
		(13 "F.Paste" user "Package Geometry/Pastemask Top")
		(15 "B.Paste" user "Package Geometry/Pastemask Bottom")
		(5 "F.SilkS" user "Ref Des/Silkscreen Top")
		(7 "B.SilkS" user "Ref Des/Silkscreen Bottom")
		(1 "F.Mask" user "Board Geometry/Soldermask Top")
		(3 "B.Mask" user "Board Geometry/Soldermask Bottom")
		(17 "Dwgs.User" user "User.Drawings")
		(19 "Cmts.User" user "User.Comments")
		(21 "Eco1.User" user "User.Eco1")
		(23 "Eco2.User" user "User.Eco2")
		(25 "Edge.Cuts" user "Board Geometry/Outline")
		(27 "Margin" user)
		(31 "F.CrtYd" user "Package Geometry/Place Bound Top")
		(29 "B.CrtYd" user "Package Geometry/Place Bound Bottom")
		(35 "F.Fab" user "Ref Des/Assembly Top")
		(33 "B.Fab" user "Ref Des/Assembly Bottom")
		(45 "User.4" user "COMPVAL_TYPE_BOTTOM")
	)
	(footprint ""
		(layer "F.Cu")
		(at 16.129 47.498 -90)
		(property "Reference" "TP49"
			(at 0.02667 4.191 0)
			(unlocked yes)
			(layer "F.SilkS")
			(effects
				(font
					(size 0.7874 0.5842)
					(thickness 0.127)
				)
				(justify left)
			)
		)
		(property "Value" "*"
			(at -0.4826 -0.14732 270)
			(unlocked yes)
			(layer "F.Fab")
			(hide yes)
			(effects
				(font
					(size 1.27 0.9652)
					(thickness 0.000001)
				)
				(justify left)
			)
		)
		(property "Device Type" "TP_SMALL"
			(at -0.4826 -0.14732 270)
			(unlocked yes)
			(layer "F.Fab")
			(hide yes)
			(effects
				(font
					(size 1.27 0.9652)
					(thickness 0.000001)
				)
				(justify left)
			)
		)
		(duplicate_pad_numbers_are_jumpers no)
		(fp_line
			(start -0.8636 0.8636)
			(end 0.8636 0.8636)
			(stroke
				(width 0.1524)
				(type default)
			)
			(layer "F.SilkS")
		)
		(fp_line
			(start 0.8636 0.8636)
			(end 0.8636 -0.8636)
			(stroke
				(width 0.1524)
				(type default)
			)
			(layer "F.SilkS")
		)
		(fp_line
			(start -0.8636 -0.8636)
			(end -0.8636 0.8636)
			(stroke
				(width 0.1524)
				(type default)
			)
			(layer "F.SilkS")
		)
		(fp_line
			(start 0.8636 -0.8636)
			(end -0.8636 -0.8636)
			(stroke
				(width 0.1524)
				(type default)
			)
			(layer "F.SilkS")
		)
		(fp_poly
			(pts
				(xy -0.635 -0.635) (xy -0.635 0.635) (xy 0.635 0.635) (xy 0.635 -0.635)
			)
			(stroke
				(width 0)
				(type default)
			)
			(fill no)
			(layer "F.CrtYd")
		)
		(pad "1" smd rect
			(at 0 0 270)
			(size 1.27 1.27)
			(layers "F.Cu" "F.Mask" "F.Paste")
			(net "GND")
		)
	)
)
